# T6G (Grand Teton) — schematic netlist excerpt (pin names and nets, part order shuffled) for the footprints in the layout excerpt that follows; sources: Cadence DE-HDL packaged netlist, KiCad conversion of 04192023_DAF0TMB3IC0_F0TG_MB_C_brd_V02_OCP.brd

R6279  Q_RES  0 5% CHIP  pkg 0402LF  page 179 : A = SMB_USB_CPU0_HUB1_SDA ; B = SMB_USB_HUB2_TI_SDA_MRP_PRT_CTL2
R1178  Q_RES  33.2 1% CHIP  pkg 0402LF  page 142 : A = OCP_V3_2_P3V3_R3_PWRGD ; B = HP_LVC3_OCP_V3_2_PWRGD_R1

(kicad_pcb
	(version 20260206)
	(generator "pcbnew")
	(generator_version "10.0")
	(general
		(thickness 1.6)
		(legacy_teardrops no)
	)
	(paper "A4")
	(title_block
		(title "04192023_DAF0TMB3IC0_F0TG_MB_C_brd_V02_OCP.brd")
		(comment 1 "Grand Teton / footprints 1175-1176 of 8354")
	)
	(layers
		(0 "F.Cu" signal "TOP")
		(4 "In1.Cu" signal "GND")
		(6 "In2.Cu" signal "IN1")
		(8 "In3.Cu" signal "GND1")
		(10 "In4.Cu" signal "IN2")
		(12 "In5.Cu" signal "GND2")
		(14 "In6.Cu" signal "IN3")
		(16 "In7.Cu" signal "GND3")
		(18 "In8.Cu" signal "VCC")
		(20 "In9.Cu" signal "VCC1")
		(22 "In10.Cu" signal "GND4")
		(24 "In11.Cu" signal "IN4")
		(26 "In12.Cu" signal "GND5")
		(28 "In13.Cu" signal "IN5")
		(30 "In14.Cu" signal "GND6")
		(32 "In15.Cu" signal "IN6")
		(34 "In16.Cu" signal "GND7")
		(2 "B.Cu" signal "BOTTOM")
		(9 "F.Adhes" user "F.Adhesive")
		(11 "B.Adhes" user "B.Adhesive")
		(13 "F.Paste" user "Package Geometry/Pastemask Top")
		(15 "B.Paste" user "Package Geometry/Pastemask Bottom")
		(5 "F.SilkS" user "Ref Des/Silkscreen Top")
		(7 "B.SilkS" user "Ref Des/Silkscreen Bottom")
		(1 "F.Mask" user "Board Geometry/Soldermask Top")
		(3 "B.Mask" user "Board Geometry/Soldermask Bottom")
		(17 "Dwgs.User" user "User.Drawings")
		(19 "Cmts.User" user "User.Comments")
		(21 "Eco1.User" user "User.Eco1")
		(23 "Eco2.User" user "User.Eco2")
		(25 "Edge.Cuts" user "Board Geometry/Outline")
		(27 "Margin" user)
		(31 "F.CrtYd" user "Package Geometry/Place Bound Top")
		(29 "B.CrtYd" user "Package Geometry/Place Bound Bottom")
		(35 "F.Fab" user "Ref Des/Assembly Top")
		(33 "B.Fab" user "Ref Des/Assembly Bottom")
	)
	(footprint ""
		(layer "F.Cu")
		(at 68.961 -54.61)
		(property "Reference" "R1178"
			(at 0 0 0)
			(layer "F.SilkS")
			(hide yes)
			(effects
				(font
					(size 1.27 1.27)
				)
			)
		)
		(property "Value" ""
			(at 0 0 0)
			(layer "F.Fab")
			(effects
				(font
					(size 1.27 1.27)
				)
			)
		)
		(duplicate_pad_numbers_are_jumpers no)
		(fp_line
			(start -0.7874 -0.4064)
			(end 0.7874 -0.4064)
			(stroke
				(width 0.1524)
				(type default)
			)
			(layer "F.SilkS")
		)
		(fp_line
			(start -0.7874 0.4064)
			(end -0.7874 -0.4064)
			(stroke
				(width 0.1524)
				(type default)
			)
			(layer "F.SilkS")
		)
		(fp_line
			(start 0.7874 -0.4064)
			(end 0.7874 0.4064)
			(stroke
				(width 0.1524)
				(type default)
			)
			(layer "F.SilkS")
		)
		(fp_line
			(start 0.7874 0.4064)
			(end -0.7874 0.4064)
			(stroke
				(width 0.1524)
				(type default)
			)
			(layer "F.SilkS")
		)
		(fp_line
			(start -0.67945 -0.305054)
			(end -0.12065 -0.305054)
			(stroke
				(width 0.1)
				(type default)
			)
			(layer "F.Fab")
		)
		(fp_line
			(start -0.67945 0.3048)
			(end -0.67945 -0.305054)
			(stroke
				(width 0.1)
				(type default)
			)
			(layer "F.Fab")
		)
		(fp_line
			(start -0.12065 -0.305054)
			(end -0.12065 -0.2794)
			(stroke
				(width 0.1)
				(type default)
			)
			(layer "F.Fab")
		)
		(fp_line
			(start -0.12065 -0.2794)
			(end 0.12065 -0.2794)
			(stroke
				(width 0.1)
				(type default)
			)
			(layer "F.Fab")
		)
		(fp_line
			(start -0.12065 0.2794)
			(end -0.12065 0.3048)
			(stroke
				(width 0.1)
				(type default)
			)
			(layer "F.Fab")
		)
		(fp_line
			(start -0.12065 0.3048)
			(end -0.67945 0.3048)
			(stroke
				(width 0.1)
				(type default)
			)
			(layer "F.Fab")
		)
		(fp_line
			(start 0.120396 0.2794)
			(end -0.12065 0.2794)
			(stroke
				(width 0.1)
				(type default)
			)
			(layer "F.Fab")
		)
		(fp_line
			(start 0.120396 0.3048)
			(end 0.120396 0.2794)
			(stroke
				(width 0.1)
				(type default)
			)
			(layer "F.Fab")
		)
		(fp_line
			(start 0.12065 -0.3048)
			(end 0.67945 -0.3048)
			(stroke
				(width 0.1)
				(type default)
			)
			(layer "F.Fab")
		)
		(fp_line
			(start 0.12065 -0.2794)
			(end 0.12065 -0.3048)
			(stroke
				(width 0.1)
				(type default)
			)
			(layer "F.Fab")
		)
		(fp_line
			(start 0.67945 -0.3048)
			(end 0.67945 0.3048)
			(stroke
				(width 0.1)
				(type default)
			)
			(layer "F.Fab")
		)
		(fp_line
			(start 0.67945 0.3048)
			(end 0.120396 0.3048)
			(stroke
				(width 0.1)
				(type default)
			)
			(layer "F.Fab")
		)
		(pad "1" smd circle
			(at -0.40005 0)
			(size 0 0)
			(layers "F.Cu" "F.Mask" "F.Paste")
			(net "OCP_V3_2_P3V3_R3_PWRGD")
		)
		(pad "2" smd circle
			(at 0.40005 0)
			(size 0 0)
			(layers "F.Cu" "F.Mask" "F.Paste")
			(net "HP_LVC3_OCP_V3_2_PWRGD_R1")
		)
	)
	(footprint ""
		(layer "F.Cu")
		(at 120.395238 -41.17975 -90)
		(property "Reference" "R6279"
			(at 0 0 270)
			(layer "F.SilkS")
			(hide yes)
			(effects
				(font
					(size 1.27 1.27)
				)
			)
		)
		(property "Value" ""
			(at 0 0 270)
			(layer "F.Fab")
			(effects
				(font
					(size 1.27 1.27)
				)
			)
		)
		(duplicate_pad_numbers_are_jumpers no)
		(fp_line
			(start -0.7874 0.4064)
			(end -0.7874 -0.4064)
			(stroke
				(width 0.1524)
				(type default)
			)
			(layer "F.SilkS")
		)
		(fp_line
			(start 0.7874 0.4064)
			(end -0.7874 0.4064)
			(stroke
				(width 0.1524)
				(type default)
			)
			(layer "F.SilkS")
		)
		(fp_line
			(start -0.7874 -0.4064)
			(end 0.7874 -0.4064)
			(stroke
				(width 0.1524)
				(type default)
			)
			(layer "F.SilkS")
		)
		(fp_line
			(start 0.7874 -0.4064)
			(end 0.7874 0.4064)
			(stroke
				(width 0.1524)
				(type default)
			)
			(layer "F.SilkS")
		)
		(fp_line
			(start -0.67945 0.3048)
			(end -0.67945 -0.305054)
			(stroke
				(width 0.1)
				(type default)
			)
			(layer "F.Fab")
		)
		(fp_line
			(start -0.12065 0.3048)
			(end -0.67945 0.3048)
			(stroke
				(width 0.1)
				(type default)
			)
			(layer "F.Fab")
		)
		(fp_line
			(start 0.120396 0.3048)
			(end 0.120396 0.2794)
			(stroke
				(width 0.1)
				(type default)
			)
			(layer "F.Fab")
		)
		(fp_line
			(start 0.67945 0.3048)
			(end 0.120396 0.3048)
			(stroke
				(width 0.1)
				(type default)
			)
			(layer "F.Fab")
		)
		(fp_line
			(start -0.12065 0.2794)
			(end -0.12065 0.3048)
			(stroke
				(width 0.1)
				(type default)
			)
			(layer "F.Fab")
		)
		(fp_line
			(start 0.120396 0.2794)
			(end -0.12065 0.2794)
			(stroke
				(width 0.1)
				(type default)
			)
			(layer "F.Fab")
		)
		(fp_line
			(start -0.12065 -0.2794)
			(end 0.12065 -0.2794)
			(stroke
				(width 0.1)
				(type default)
			)
			(layer "F.Fab")
		)
		(fp_line
			(start 0.12065 -0.2794)
			(end 0.12065 -0.3048)
			(stroke
				(width 0.1)
				(type default)
			)
			(layer "F.Fab")
		)
		(fp_line
			(start 0.12065 -0.3048)
			(end 0.67945 -0.3048)
			(stroke
				(width 0.1)
				(type default)
			)
			(layer "F.Fab")
		)
		(fp_line
			(start 0.67945 -0.3048)
			(end 0.67945 0.3048)
			(stroke
				(width 0.1)
				(type default)
			)
			(layer "F.Fab")
		)
		(fp_line
			(start -0.67945 -0.305054)
			(end -0.12065 -0.305054)
			(stroke
				(width 0.1)
				(type default)
			)
			(layer "F.Fab")
		)
		(fp_line
			(start -0.12065 -0.305054)
			(end -0.12065 -0.2794)
			(stroke
				(width 0.1)
				(type default)
			)
			(layer "F.Fab")
		)
		(pad "1" smd circle
			(at -0.40005 0 270)
			(size 0 0)
			(layers "F.Cu" "F.Mask" "F.Paste")
			(net "SMB_USB_CPU0_HUB1_SDA")
		)
		(pad "2" smd circle
			(at 0.40005 0 270)
			(size 0 0)
			(layers "F.Cu" "F.Mask" "F.Paste")
			(net "SMB_USB_HUB2_TI_SDA_MRP_PRT_CTL2")
		)
	)
)
